(kicad_pcb
	(version 20241229)
	(generator "pcbnew")
	(generator_version "9.0")
	(general
		(thickness 1.61)
		(legacy_teardrops no)
	)
	(paper "A3")
	(title_block
		(title "RDIMM DDR5 Tester")
		(date "2026-05-21")
		(rev "2.2.0")
		(company "Antmicro")
		(comment 9 "footprint 372 of 796 (J10), pads 1-98 of 98")
	)
	(layers
		(0 "F.Cu" signal)
		(4 "In1.Cu" power)
		(6 "In2.Cu" mixed)
		(8 "In3.Cu" power)
		(10 "In4.Cu" mixed)
		(12 "In5.Cu" power)
		(14 "In6.Cu" mixed)
		(16 "In7.Cu" power)
		(18 "In8.Cu" power)
		(20 "In9.Cu" mixed)
		(22 "In10.Cu" power)
		(2 "B.Cu" signal)
		(9 "F.Adhes" user "F.Adhesive")
		(11 "B.Adhes" user "B.Adhesive")
		(13 "F.Paste" user)
		(15 "B.Paste" user)
		(5 "F.SilkS" user "F.Silkscreen")
		(7 "B.SilkS" user "B.Silkscreen")
		(1 "F.Mask" user)
		(3 "B.Mask" user)
		(17 "Dwgs.User" user "User.Drawings")
		(19 "Cmts.User" user "User.Comments")
		(21 "Eco1.User" user "User.Eco1")
		(23 "Eco2.User" user "User.Eco2")
		(25 "Edge.Cuts" user)
		(27 "Margin" user)
		(31 "F.CrtYd" user "F.Courtyard")
		(29 "B.CrtYd" user "B.Courtyard")
		(35 "F.Fab" user)
		(33 "B.Fab" user)
	)
	(footprint "antmicro-footprints:PCB-Edge_PCIexpress_x8"
		(layer "F.Cu")
		(at 145.65 199.25)
		(descr "PCIexpress x8")
		(tags "PCIexpress")
		(property "Reference" "J10"
			(at -0.025 -3.175 0)
			(layer "F.SilkS")
			(hide yes)
			(effects
				(font
					(size 0.7 0.7)
					(thickness 0.15)
				)
				(justify left bottom)
			)
		)
		(property "Value" "PCB-Edge_PCIexpress_x8"
			(at -0.8 7.3 0)
			(layer "F.Fab")
			(effects
				(font
					(size 0.7 0.7)
					(thickness 0.15)
				)
				(justify left bottom)
			)
		)
		(property "Author" "Antmicro"
			(at 0 0 0)
			(unlocked yes)
			(layer "F.Fab")
			(hide yes)
			(effects
				(font
					(size 1 1)
					(thickness 0.15)
				)
			)
		)
		(property "License" "Apache-2.0"
			(at 0 0 0)
			(unlocked yes)
			(layer "F.Fab")
			(hide yes)
			(effects
				(font
					(size 1 1)
					(thickness 0.15)
				)
			)
		)
		(sheetname "/PCIe connector/")
		(sheetfile "pcie-connector.kicad_sch")
		(attr exclude_from_pos_files exclude_from_bom)
		(pad "A1" connect rect
			(at 0 -0.55)
			(size 0.7 3.2)
			(layers "B.Cu" "B.Mask")
			(net 174 "/PCIe connector/PRSNT#1")
			(pinfunction "~{PRSNT1}")
			(pintype "passive")
		)
		(pad "A2" connect rect
			(at 1 0)
			(size 0.7 4.3)
			(layers "B.Cu" "B.Mask")
			(net 10 "+12V")
			(pinfunction "12V")
			(pintype "power_in")
		)
		(pad "A3" connect rect
			(at 2 0)
			(size 0.7 4.3)
			(layers "B.Cu" "B.Mask")
			(net 10 "+12V")
			(pinfunction "12V")
			(pintype "passive")
		)
		(pad "A4" connect rect
			(at 3 0)
			(size 0.7 4.3)
			(layers "B.Cu" "B.Mask")
			(net 1 "GND")
			(pinfunction "GND")
			(pintype "passive")
		)
		(pad "A5" connect rect
			(at 4 0)
			(size 0.7 4.3)
			(layers "B.Cu" "B.Mask")
			(net 260 "unconnected-(J10-TCK-PadA5)")
			(pinfunction "TCK")
			(pintype "input+no_connect")
		)
		(pad "A6" connect rect
			(at 5 0)
			(size 0.7 4.3)
			(layers "B.Cu" "B.Mask")
			(net 261 "unconnected-(J10-TDI-PadA6)")
			(pinfunction "TDI")
			(pintype "input+no_connect")
		)
		(pad "A7" connect rect
			(at 6 0)
			(size 0.7 4.3)
			(layers "B.Cu" "B.Mask")
			(net 262 "unconnected-(J10-TDO-PadA7)")
			(pinfunction "TDO")
			(pintype "output+no_connect")
		)
		(pad "A8" connect rect
			(at 7 0)
			(size 0.7 4.3)
			(layers "B.Cu" "B.Mask")
			(net 263 "unconnected-(J10-TMS-PadA8)")
			(pinfunction "TMS")
			(pintype "input+no_connect")
		)
		(pad "A9" connect rect
			(at 8 0)
			(size 0.7 4.3)
			(layers "B.Cu" "B.Mask")
			(net 815 "unconnected-(J10-3V3-PadA10)_1")
			(pinfunction "3V3")
			(pintype "passive+no_connect")
		)
		(pad "A10" connect rect
			(at 9 0)
			(size 0.7 4.3)
			(layers "B.Cu" "B.Mask")
			(net 816 "unconnected-(J10-3V3-PadA10)_2")
			(pinfunction "3V3")
			(pintype "power_in+no_connect")
		)
		(pad "A11" connect rect
			(at 10 0)
			(size 0.7 4.3)
			(layers "B.Cu" "B.Mask")
			(net 98 "PCIE.PWRGD")
			(pinfunction "~{PERST}")
			(pintype "open_collector")
		)
		(pad "A12" connect rect
			(at 13 0)
			(size 0.7 4.3)
			(layers "B.Cu" "B.Mask")
			(net 1 "GND")
			(pinfunction "GND")
			(pintype "power_in")
		)
		(pad "A13" connect rect
			(at 14 0)
			(size 0.7 4.3)
			(layers "B.Cu" "B.Mask")
			(net 11 "/FPGA MGT Interface/PCIE.CLK_P")
			(pinfunction "REFCLK_p")
			(pintype "input")
		)
		(pad "A14" connect rect
			(at 15 0)
			(size 0.7 4.3)
			(layers "B.Cu" "B.Mask")
			(net 13 "/FPGA MGT Interface/PCIE.CLK_N")
			(pinfunction "REFCLK_n")
			(pintype "input")
		)
		(pad "A15" connect rect
			(at 16 0)
			(size 0.7 4.3)
			(layers "B.Cu" "B.Mask")
			(net 1 "GND")
			(pinfunction "GND")
			(pintype "passive")
		)
		(pad "A16" connect rect
			(at 17 0)
			(size 0.7 4.3)
			(layers "B.Cu" "B.Mask")
			(net 21 "/FPGA MGT Interface/PCIE.TXD0_P")
			(pinfunction "HSI0_p")
			(pintype "output")
		)
		(pad "A17" connect rect
			(at 18 0)
			(size 0.7 4.3)
			(layers "B.Cu" "B.Mask")
			(net 27 "/FPGA MGT Interface/PCIE.TXD0_N")
			(pinfunction "HSI0_n")
			(pintype "output")
		)
		(pad "A18" connect rect
			(at 19 0)
			(size 0.7 4.3)
			(layers "B.Cu" "B.Mask")
			(net 1 "GND")
			(pinfunction "GND")
			(pintype "passive")
		)
		(pad "A19" connect rect
			(at 20 0)
			(size 0.7 4.3)
			(layers "B.Cu" "B.Mask")
			(net 265 "unconnected-(J10-NC-PadA19)")
			(pinfunction "NC")
			(pintype "no_connect")
		)
		(pad "A20" connect rect
			(at 21 0)
			(size 0.7 4.3)
			(layers "B.Cu" "B.Mask")
			(net 1 "GND")
			(pinfunction "GND")
			(pintype "passive")
		)
		(pad "A21" connect rect
			(at 22 0)
			(size 0.7 4.3)
			(layers "B.Cu" "B.Mask")
			(net 19 "/FPGA MGT Interface/PCIE.TXD1_P")
			(pinfunction "HSI1_p")
			(pintype "output")
		)
		(pad "A22" connect rect
			(at 23 0)
			(size 0.7 4.3)
			(layers "B.Cu" "B.Mask")
			(net 30 "/FPGA MGT Interface/PCIE.TXD1_N")
			(pinfunction "HSI1_n")
			(pintype "output")
		)
		(pad "A23" connect rect
			(at 24 0)
			(size 0.7 4.3)
			(layers "B.Cu" "B.Mask")
			(net 1 "GND")
			(pinfunction "GND")
			(pintype "passive")
		)
		(pad "A24" connect rect
			(at 25 0)
			(size 0.7 4.3)
			(layers "B.Cu" "B.Mask")
			(net 1 "GND")
			(pinfunction "GND")
			(pintype "passive")
		)
		(pad "A25" connect rect
			(at 26 0)
			(size 0.7 4.3)
			(layers "B.Cu" "B.Mask")
			(net 17 "/FPGA MGT Interface/PCIE.TXD2_P")
			(pinfunction "HSI2_p")
			(pintype "output")
		)
		(pad "A26" connect rect
			(at 27 0)
			(size 0.7 4.3)
			(layers "B.Cu" "B.Mask")
			(net 25 "/FPGA MGT Interface/PCIE.TXD2_N")
			(pinfunction "HSI2_n")
			(pintype "output")
		)
		(pad "A27" connect rect
			(at 28 0)
			(size 0.7 4.3)
			(layers "B.Cu" "B.Mask")
			(net 1 "GND")
			(pinfunction "GND")
			(pintype "passive")
		)
		(pad "A28" connect rect
			(at 29 0)
			(size 0.7 4.3)
			(layers "B.Cu" "B.Mask")
			(net 1 "GND")
			(pinfunction "GND")
			(pintype "passive")
		)
		(pad "A29" connect rect
			(at 30 0)
			(size 0.7 4.3)
			(layers "B.Cu" "B.Mask")
			(net 15 "/FPGA MGT Interface/PCIE.TXD3_P")
			(pinfunction "HSI3_p")
			(pintype "output")
		)
		(pad "A30" connect rect
			(at 31 0)
			(size 0.7 4.3)
			(layers "B.Cu" "B.Mask")
			(net 23 "/FPGA MGT Interface/PCIE.TXD3_N")
			(pinfunction "HSI3_n")
			(pintype "output")
		)
		(pad "A31" connect rect
			(at 32 0)
			(size 0.7 4.3)
			(layers "B.Cu" "B.Mask")
			(net 1 "GND")
			(pinfunction "GND")
			(pintype "passive")
		)
		(pad "A32" connect rect
			(at 33 0)
			(size 0.7 4.3)
			(layers "B.Cu" "B.Mask")
			(net 574 "unconnected-(J10-NC-PadA32)")
			(pinfunction "NC")
			(pintype "no_connect")
		)
		(pad "A33" connect rect
			(at 34 0)
			(size 0.7 4.3)
			(layers "B.Cu" "B.Mask")
			(net 575 "unconnected-(J10-NC-PadA33)")
			(pinfunction "NC")
			(pintype "no_connect")
		)
		(pad "A34" connect rect
			(at 35 0)
			(size 0.7 4.3)
			(layers "B.Cu" "B.Mask")
			(net 1 "GND")
			(pinfunction "GND")
			(pintype "passive")
		)
		(pad "A35" connect rect
			(at 36 0)
			(size 0.7 4.3)
			(layers "B.Cu" "B.Mask")
			(net 258 "/FPGA MGT Interface/PCIE.TXD4_P")
			(pinfunction "HSI4_p")
			(pintype "output")
		)
		(pad "A36" connect rect
			(at 37 0)
			(size 0.7 4.3)
			(layers "B.Cu" "B.Mask")
			(net 259 "/FPGA MGT Interface/PCIE.TXD4_N")
			(pinfunction "HSI4_n")
			(pintype "output")
		)
		(pad "A37" connect rect
			(at 38 0)
			(size 0.7 4.3)
			(layers "B.Cu" "B.Mask")
			(net 1 "GND")
			(pinfunction "GND")
			(pintype "passive")
		)
		(pad "A38" connect rect
			(at 39 0)
			(size 0.7 4.3)
			(layers "B.Cu" "B.Mask")
			(net 1 "GND")
			(pinfunction "GND")
			(pintype "passive")
		)
		(pad "A39" connect rect
			(at 40 0)
			(size 0.7 4.3)
			(layers "B.Cu" "B.Mask")
			(net 257 "/FPGA MGT Interface/PCIE.TXD5_P")
			(pinfunction "HSI5_p")
			(pintype "output")
		)
		(pad "A40" connect rect
			(at 41 0)
			(size 0.7 4.3)
			(layers "B.Cu" "B.Mask")
			(net 252 "/FPGA MGT Interface/PCIE.TXD5_N")
			(pinfunction "HSI5_n")
			(pintype "output")
		)
		(pad "A41" connect rect
			(at 42 0)
			(size 0.7 4.3)
			(layers "B.Cu" "B.Mask")
			(net 1 "GND")
			(pinfunction "GND")
			(pintype "passive")
		)
		(pad "A42" connect rect
			(at 43 0)
			(size 0.7 4.3)
			(layers "B.Cu" "B.Mask")
			(net 1 "GND")
			(pinfunction "GND")
			(pintype "passive")
		)
		(pad "A43" connect rect
			(at 44 0)
			(size 0.7 4.3)
			(layers "B.Cu" "B.Mask")
			(net 255 "/FPGA MGT Interface/PCIE.TXD6_P")
			(pinfunction "HSI6_p")
			(pintype "output")
		)
		(pad "A44" connect rect
			(at 45 0)
			(size 0.7 4.3)
			(layers "B.Cu" "B.Mask")
			(net 256 "/FPGA MGT Interface/PCIE.TXD6_N")
			(pinfunction "HSI6_n")
			(pintype "output")
		)
		(pad "A45" connect rect
			(at 46 0)
			(size 0.7 4.3)
			(layers "B.Cu" "B.Mask")
			(net 1 "GND")
			(pinfunction "GND")
			(pintype "passive")
		)
		(pad "A46" connect rect
			(at 47 0)
			(size 0.7 4.3)
			(layers "B.Cu" "B.Mask")
			(net 1 "GND")
			(pinfunction "GND")
			(pintype "passive")
		)
		(pad "A47" connect rect
			(at 48 0)
			(size 0.7 4.3)
			(layers "B.Cu" "B.Mask")
			(net 253 "/FPGA MGT Interface/PCIE.TXD7_P")
			(pinfunction "HSI7_p")
			(pintype "output")
		)
		(pad "A48" connect rect
			(at 49 0)
			(size 0.7 4.3)
			(layers "B.Cu" "B.Mask")
			(net 254 "/FPGA MGT Interface/PCIE.TXD7_N")
			(pinfunction "HSI7_n")
			(pintype "output")
		)
		(pad "A49" connect rect
			(at 50 0)
			(size 0.7 4.3)
			(layers "B.Cu" "B.Mask")
			(net 1 "GND")
			(pinfunction "GND")
			(pintype "passive")
		)
		(pad "B1" connect rect
			(at 0 0)
			(size 0.7 4.3)
			(layers "F.Cu" "F.Mask")
			(net 10 "+12V")
			(pinfunction "12V")
			(pintype "passive")
		)
		(pad "B2" connect rect
			(at 1 0)
			(size 0.7 4.3)
			(layers "F.Cu" "F.Mask")
			(net 10 "+12V")
			(pinfunction "12V")
			(pintype "passive")
		)
		(pad "B3" connect rect
			(at 2 0)
			(size 0.7 4.3)
			(layers "F.Cu" "F.Mask")
			(net 10 "+12V")
			(pinfunction "12V")
			(pintype "passive")
		)
		(pad "B4" connect rect
			(at 3 0)
			(size 0.7 4.3)
			(layers "F.Cu" "F.Mask")
			(net 1 "GND")
			(pinfunction "GND")
			(pintype "passive")
		)
		(pad "B5" connect rect
			(at 4 0)
			(size 0.7 4.3)
			(layers "F.Cu" "F.Mask")
			(net 576 "unconnected-(J10-SMCLK-PadB5)")
			(pinfunction "SMCLK")
			(pintype "open_collector+no_connect")
		)
		(pad "B6" connect rect
			(at 5 0)
			(size 0.7 4.3)
			(layers "F.Cu" "F.Mask")
			(net 577 "unconnected-(J10-SMDAT-PadB6)")
			(pinfunction "SMDAT")
			(pintype "open_collector+no_connect")
		)
		(pad "B7" connect rect
			(at 6 0)
			(size 0.7 4.3)
			(layers "F.Cu" "F.Mask")
			(net 1 "GND")
			(pinfunction "GND")
			(pintype "passive")
		)
		(pad "B8" connect rect
			(at 7 0)
			(size 0.7 4.3)
			(layers "F.Cu" "F.Mask")
			(net 264 "unconnected-(J10-3V3-PadA10)")
			(pinfunction "3V3")
			(pintype "passive+no_connect")
		)
		(pad "B9" connect rect
			(at 8 0)
			(size 0.7 4.3)
			(layers "F.Cu" "F.Mask")
			(net 578 "unconnected-(J10-~{TRST}-PadB9)")
			(pinfunction "~{TRST}")
			(pintype "input+no_connect")
		)
		(pad "B10" connect rect
			(at 9 0)
			(size 0.7 4.3)
			(layers "F.Cu" "F.Mask")
			(net 579 "unconnected-(J10-3V3AUX-PadB10)")
			(pinfunction "3V3AUX")
			(pintype "power_in+no_connect")
		)
		(pad "B11" connect rect
			(at 10 0)
			(size 0.7 4.3)
			(layers "F.Cu" "F.Mask")
			(net 580 "unconnected-(J10-~{WAKE}-PadB11)")
			(pinfunction "~{WAKE}")
			(pintype "open_collector+no_connect")
		)
		(pad "B12" connect rect
			(at 13 0)
			(size 0.7 4.3)
			(layers "F.Cu" "F.Mask")
			(net 581 "unconnected-(J10-~{CLKREQ}-PadB12)")
			(pinfunction "~{CLKREQ}")
			(pintype "open_collector+no_connect")
		)
		(pad "B13" connect rect
			(at 14 0)
			(size 0.7 4.3)
			(layers "F.Cu" "F.Mask")
			(net 1 "GND")
			(pinfunction "GND")
			(pintype "passive")
		)
		(pad "B14" connect rect
			(at 15 0)
			(size 0.7 4.3)
			(layers "F.Cu" "F.Mask")
			(net 332 "/FPGA MGT Interface/PCIE.RXD0_P")
			(pinfunction "HSO0_p")
			(pintype "input")
		)
		(pad "B15" connect rect
			(at 16 0)
			(size 0.7 4.3)
			(layers "F.Cu" "F.Mask")
			(net 333 "/FPGA MGT Interface/PCIE.RXD0_N")
			(pinfunction "HSO0_n")
			(pintype "input")
		)
		(pad "B16" connect rect
			(at 17 0)
			(size 0.7 4.3)
			(layers "F.Cu" "F.Mask")
			(net 1 "GND")
			(pinfunction "GND")
			(pintype "passive")
		)
		(pad "B17" connect rect
			(at 18 0)
			(size 0.7 4.3)
			(layers "F.Cu" "F.Mask")
			(net 175 "/PCIe connector/x1")
			(pinfunction "~{PRSNT2_x1}")
			(pintype "passive")
		)
		(pad "B18" connect rect
			(at 19 0)
			(size 0.7 4.3)
			(layers "F.Cu" "F.Mask")
			(net 1 "GND")
			(pinfunction "GND")
			(pintype "passive")
		)
		(pad "B19" connect rect
			(at 20 0)
			(size 0.7 4.3)
			(layers "F.Cu" "F.Mask")
			(net 334 "/FPGA MGT Interface/PCIE.RXD1_P")
			(pinfunction "HSO1_p")
			(pintype "input")
		)
		(pad "B20" connect rect
			(at 21 0)
			(size 0.7 4.3)
			(layers "F.Cu" "F.Mask")
			(net 335 "/FPGA MGT Interface/PCIE.RXD1_N")
			(pinfunction "HSO1_n")
			(pintype "input")
		)
		(pad "B21" connect rect
			(at 22 0)
			(size 0.7 4.3)
			(layers "F.Cu" "F.Mask")
			(net 1 "GND")
			(pinfunction "GND")
			(pintype "passive")
		)
		(pad "B22" connect rect
			(at 23 0)
			(size 0.7 4.3)
			(layers "F.Cu" "F.Mask")
			(net 1 "GND")
			(pinfunction "GND")
			(pintype "passive")
		)
		(pad "B23" connect rect
			(at 24 0)
			(size 0.7 4.3)
			(layers "F.Cu" "F.Mask")
			(net 336 "/FPGA MGT Interface/PCIE.RXD2_P")
			(pinfunction "HSO2_p")
			(pintype "input")
		)
		(pad "B24" connect rect
			(at 25 0)
			(size 0.7 4.3)
			(layers "F.Cu" "F.Mask")
			(net 337 "/FPGA MGT Interface/PCIE.RXD2_N")
			(pinfunction "HSO2_n")
			(pintype "input")
		)
		(pad "B25" connect rect
			(at 26 0)
			(size 0.7 4.3)
			(layers "F.Cu" "F.Mask")
			(net 1 "GND")
			(pinfunction "GND")
			(pintype "passive")
		)
		(pad "B26" connect rect
			(at 27 0)
			(size 0.7 4.3)
			(layers "F.Cu" "F.Mask")
			(net 1 "GND")
			(pinfunction "GND")
			(pintype "passive")
		)
		(pad "B27" connect rect
			(at 28 0)
			(size 0.7 4.3)
			(layers "F.Cu" "F.Mask")
			(net 338 "/FPGA MGT Interface/PCIE.RXD3_P")
			(pinfunction "HSO3_p")
			(pintype "input")
		)
		(pad "B28" connect rect
			(at 29 0)
			(size 0.7 4.3)
			(layers "F.Cu" "F.Mask")
			(net 339 "/FPGA MGT Interface/PCIE.RXD3_N")
			(pinfunction "HSO3_n")
			(pintype "input")
		)
		(pad "B29" connect rect
			(at 30 0)
			(size 0.7 4.3)
			(layers "F.Cu" "F.Mask")
			(net 1 "GND")
			(pinfunction "GND")
			(pintype "passive")
		)
		(pad "B30" connect rect
			(at 31 0)
			(size 0.7 4.3)
			(layers "F.Cu" "F.Mask")
			(net 582 "unconnected-(J10-~{PWRBRK}-PadB30)")
			(pinfunction "~{PWRBRK}")
			(pintype "open_collector+no_connect")
		)
		(pad "B31" connect rect
			(at 32 0)
			(size 0.7 4.3)
			(layers "F.Cu" "F.Mask")
			(net 176 "/PCIe connector/x4")
			(pinfunction "~{PRSNT2_x4}")
			(pintype "passive")
		)
		(pad "B32" connect rect
			(at 33 0)
			(size 0.7 4.3)
			(layers "F.Cu" "F.Mask")
			(net 1 "GND")
			(pinfunction "GND")
			(pintype "passive")
		)
		(pad "B33" connect rect
			(at 34 0)
			(size 0.7 4.3)
			(layers "F.Cu" "F.Mask")
			(net 583 "/FPGA MGT Interface/PCIE.RXD4_P")
			(pinfunction "HSO4_p")
			(pintype "input")
		)
		(pad "B34" connect rect
			(at 35 0)
			(size 0.7 4.3)
			(layers "F.Cu" "F.Mask")
			(net 584 "/FPGA MGT Interface/PCIE.RXD4_N")
			(pinfunction "HSO4_n")
			(pintype "input")
		)
		(pad "B35" connect rect
			(at 36 0)
			(size 0.7 4.3)
			(layers "F.Cu" "F.Mask")
			(net 1 "GND")
			(pinfunction "GND")
			(pintype "passive")
		)
		(pad "B36" connect rect
			(at 37 0)
			(size 0.7 4.3)
			(layers "F.Cu" "F.Mask")
			(net 1 "GND")
			(pinfunction "GND")
			(pintype "passive")
		)
		(pad "B37" connect rect
			(at 38 0)
			(size 0.7 4.3)
			(layers "F.Cu" "F.Mask")
			(net 585 "/FPGA MGT Interface/PCIE.RXD5_P")
			(pinfunction "HSO5_p")
			(pintype "input")
		)
		(pad "B38" connect rect
			(at 39 0)
			(size 0.7 4.3)
			(layers "F.Cu" "F.Mask")
			(net 586 "/FPGA MGT Interface/PCIE.RXD5_N")
			(pinfunction "HSO5_n")
			(pintype "input")
		)
		(pad "B39" connect rect
			(at 40 0)
			(size 0.7 4.3)
			(layers "F.Cu" "F.Mask")
			(net 1 "GND")
			(pinfunction "GND")
			(pintype "passive")
		)
		(pad "B40" connect rect
			(at 41 0)
			(size 0.7 4.3)
			(layers "F.Cu" "F.Mask")
			(net 1 "GND")
			(pinfunction "GND")
			(pintype "passive")
		)
		(pad "B41" connect rect
			(at 42 0)
			(size 0.7 4.3)
			(layers "F.Cu" "F.Mask")
			(net 587 "/FPGA MGT Interface/PCIE.RXD6_P")
			(pinfunction "HSO6_p")
			(pintype "input")
		)
		(pad "B42" connect rect
			(at 43 0)
			(size 0.7 4.3)
			(layers "F.Cu" "F.Mask")
			(net 588 "/FPGA MGT Interface/PCIE.RXD6_N")
			(pinfunction "HSO6_n")
			(pintype "input")
		)
		(pad "B43" connect rect
			(at 44 0)
			(size 0.7 4.3)
			(layers "F.Cu" "F.Mask")
			(net 1 "GND")
			(pinfunction "GND")
			(pintype "passive")
		)
		(pad "B44" connect rect
			(at 45 0)
			(size 0.7 4.3)
			(layers "F.Cu" "F.Mask")
			(net 1 "GND")
			(pinfunction "GND")
			(pintype "passive")
		)
		(pad "B45" connect rect
			(at 46 0)
			(size 0.7 4.3)
			(layers "F.Cu" "F.Mask")
			(net 589 "/FPGA MGT Interface/PCIE.RXD7_P")
			(pinfunction "HSO7_p")
			(pintype "input")
		)
		(pad "B46" connect rect
			(at 47 0)
			(size 0.7 4.3)
			(layers "F.Cu" "F.Mask")
			(net 590 "/FPGA MGT Interface/PCIE.RXD7_N")
			(pinfunction "HSO7_n")
			(pintype "input")
		)
		(pad "B47" connect rect
			(at 48 0)
			(size 0.7 4.3)
			(layers "F.Cu" "F.Mask")
			(net 1 "GND")
			(pinfunction "GND")
			(pintype "passive")
		)
		(pad "B48" connect rect
			(at 49 -0.55)
			(size 0.7 3.2)
			(layers "F.Cu" "F.Mask")
			(net 591 "/PCIe connector/x8")
			(pinfunction "~{PRSNT2_x8}")
			(pintype "passive")
		)
		(pad "B49" connect rect
			(at 50 0)
			(size 0.7 4.3)
			(layers "F.Cu" "F.Mask")
			(net 1 "GND")
			(pinfunction "GND")
			(pintype "passive")
		)
	)
)
